(kicad_pcb
	(version 20260206)
	(generator "pcbnew")
	(generator_version "10.0")
	(general
		(thickness 1.6)
		(legacy_teardrops no)
	)
	(paper "A4")
	(title_block
		(title "12092022_DA0F0TMDCD0_F0T_Management_Board_D_brd_V3_OCP.brd")
		(comment 1 "Grand Teton / footprints 1345-1350 of 1440")
	)
	(layers
		(0 "F.Cu" signal "TOP")
		(4 "In1.Cu" signal "GND")
		(6 "In2.Cu" signal "IN1")
		(8 "In3.Cu" signal "GND1")
		(10 "In4.Cu" signal "IN2")
		(12 "In5.Cu" signal "VCC")
		(14 "In6.Cu" signal "VCC1")
		(16 "In7.Cu" signal "IN3")
		(18 "In8.Cu" signal "GND2")
		(20 "In9.Cu" signal "IN4")
		(22 "In10.Cu" signal "GND3")
		(2 "B.Cu" signal "BOTTOM")
		(9 "F.Adhes" user "F.Adhesive")
		(11 "B.Adhes" user "B.Adhesive")
		(13 "F.Paste" user "Package Geometry/Pastemask Top")
		(15 "B.Paste" user "Package Geometry/Pastemask Bottom")
		(5 "F.SilkS" user "Ref Des/Silkscreen Top")
		(7 "B.SilkS" user "Ref Des/Silkscreen Bottom")
		(1 "F.Mask" user "Board Geometry/Soldermask Top")
		(3 "B.Mask" user "Board Geometry/Soldermask Bottom")
		(17 "Dwgs.User" user "User.Drawings")
		(19 "Cmts.User" user "User.Comments")
		(21 "Eco1.User" user "User.Eco1")
		(23 "Eco2.User" user "User.Eco2")
		(25 "Edge.Cuts" user "Board Geometry/Outline")
		(27 "Margin" user)
		(31 "F.CrtYd" user "Package Geometry/Place Bound Top")
		(29 "B.CrtYd" user "Package Geometry/Place Bound Bottom")
		(35 "F.Fab" user "Ref Des/Assembly Top")
		(33 "B.Fab" user "Ref Des/Assembly Bottom")
	)
	(footprint ""
		(layer "B.Cu")
		(at 48.514 -34.671 -90)
		(property "Reference" "R162"
			(at 0 0 90)
			(layer "B.SilkS")
			(hide yes)
			(effects
				(font
					(size 1.27 1.27)
				)
				(justify mirror)
			)
		)
		(property "Value" ""
			(at 0 0 90)
			(layer "B.Fab")
			(effects
				(font
					(size 1.27 1.27)
				)
				(justify mirror)
			)
		)
		(duplicate_pad_numbers_are_jumpers no)
		(fp_line
			(start -0.7874 0.4064)
			(end 0.7874 0.4064)
			(stroke
				(width 0.1524)
				(type default)
			)
			(layer "B.SilkS")
		)
		(fp_line
			(start 0.7874 0.4064)
			(end 0.7874 -0.4064)
			(stroke
				(width 0.1524)
				(type default)
			)
			(layer "B.SilkS")
		)
		(fp_line
			(start -0.7874 -0.4064)
			(end -0.7874 0.4064)
			(stroke
				(width 0.1524)
				(type default)
			)
			(layer "B.SilkS")
		)
		(fp_line
			(start 0.7874 -0.4064)
			(end -0.7874 -0.4064)
			(stroke
				(width 0.1524)
				(type default)
			)
			(layer "B.SilkS")
		)
		(fp_line
			(start -0.67945 0.3048)
			(end -0.120396 0.3048)
			(stroke
				(width 0.1)
				(type default)
			)
			(layer "B.Fab")
		)
		(fp_line
			(start -0.120396 0.3048)
			(end -0.120396 0.2794)
			(stroke
				(width 0.1)
				(type default)
			)
			(layer "B.Fab")
		)
		(fp_line
			(start 0.12065 0.3048)
			(end 0.67945 0.3048)
			(stroke
				(width 0.1)
				(type default)
			)
			(layer "B.Fab")
		)
		(fp_line
			(start 0.67945 0.3048)
			(end 0.67945 -0.305054)
			(stroke
				(width 0.1)
				(type default)
			)
			(layer "B.Fab")
		)
		(fp_line
			(start -0.120396 0.2794)
			(end 0.12065 0.2794)
			(stroke
				(width 0.1)
				(type default)
			)
			(layer "B.Fab")
		)
		(fp_line
			(start 0.12065 0.2794)
			(end 0.12065 0.3048)
			(stroke
				(width 0.1)
				(type default)
			)
			(layer "B.Fab")
		)
		(fp_line
			(start -0.12065 -0.2794)
			(end -0.12065 -0.3048)
			(stroke
				(width 0.1)
				(type default)
			)
			(layer "B.Fab")
		)
		(fp_line
			(start 0.12065 -0.2794)
			(end -0.12065 -0.2794)
			(stroke
				(width 0.1)
				(type default)
			)
			(layer "B.Fab")
		)
		(fp_line
			(start -0.67945 -0.3048)
			(end -0.67945 0.3048)
			(stroke
				(width 0.1)
				(type default)
			)
			(layer "B.Fab")
		)
		(fp_line
			(start -0.12065 -0.3048)
			(end -0.67945 -0.3048)
			(stroke
				(width 0.1)
				(type default)
			)
			(layer "B.Fab")
		)
		(fp_line
			(start 0.12065 -0.305054)
			(end 0.12065 -0.2794)
			(stroke
				(width 0.1)
				(type default)
			)
			(layer "B.Fab")
		)
		(fp_line
			(start 0.67945 -0.305054)
			(end 0.12065 -0.305054)
			(stroke
				(width 0.1)
				(type default)
			)
			(layer "B.Fab")
		)
		(pad "1" smd circle
			(at 0.40005 0 90)
			(size 0 0)
			(layers "B.Cu" "B.Mask" "B.Paste")
			(net "SMB_BMC_MM15_SCL")
		)
		(pad "2" smd circle
			(at -0.40005 0 90)
			(size 0 0)
			(layers "B.Cu" "B.Mask" "B.Paste")
			(net "SMB_BMC_MM15_R_SCL")
		)
	)
	(footprint ""
		(layer "B.Cu")
		(at 46.355 -96.8248 -90)
		(property "Reference" "R671"
			(at 0 0 90)
			(layer "B.SilkS")
			(hide yes)
			(effects
				(font
					(size 1.27 1.27)
				)
				(justify mirror)
			)
		)
		(property "Value" ""
			(at 0 0 90)
			(layer "B.Fab")
			(effects
				(font
					(size 1.27 1.27)
				)
				(justify mirror)
			)
		)
		(duplicate_pad_numbers_are_jumpers no)
		(fp_line
			(start -0.7874 0.4064)
			(end 0.7874 0.4064)
			(stroke
				(width 0.1524)
				(type default)
			)
			(layer "B.SilkS")
		)
		(fp_line
			(start 0.7874 0.4064)
			(end 0.7874 -0.4064)
			(stroke
				(width 0.1524)
				(type default)
			)
			(layer "B.SilkS")
		)
		(fp_line
			(start -0.7874 -0.4064)
			(end -0.7874 0.4064)
			(stroke
				(width 0.1524)
				(type default)
			)
			(layer "B.SilkS")
		)
		(fp_line
			(start 0.7874 -0.4064)
			(end -0.7874 -0.4064)
			(stroke
				(width 0.1524)
				(type default)
			)
			(layer "B.SilkS")
		)
		(fp_line
			(start -0.67945 0.3048)
			(end -0.120396 0.3048)
			(stroke
				(width 0.1)
				(type default)
			)
			(layer "B.Fab")
		)
		(fp_line
			(start -0.120396 0.3048)
			(end -0.120396 0.2794)
			(stroke
				(width 0.1)
				(type default)
			)
			(layer "B.Fab")
		)
		(fp_line
			(start 0.12065 0.3048)
			(end 0.67945 0.3048)
			(stroke
				(width 0.1)
				(type default)
			)
			(layer "B.Fab")
		)
		(fp_line
			(start 0.67945 0.3048)
			(end 0.67945 -0.305054)
			(stroke
				(width 0.1)
				(type default)
			)
			(layer "B.Fab")
		)
		(fp_line
			(start -0.120396 0.2794)
			(end 0.12065 0.2794)
			(stroke
				(width 0.1)
				(type default)
			)
			(layer "B.Fab")
		)
		(fp_line
			(start 0.12065 0.2794)
			(end 0.12065 0.3048)
			(stroke
				(width 0.1)
				(type default)
			)
			(layer "B.Fab")
		)
		(fp_line
			(start -0.12065 -0.2794)
			(end -0.12065 -0.3048)
			(stroke
				(width 0.1)
				(type default)
			)
			(layer "B.Fab")
		)
		(fp_line
			(start 0.12065 -0.2794)
			(end -0.12065 -0.2794)
			(stroke
				(width 0.1)
				(type default)
			)
			(layer "B.Fab")
		)
		(fp_line
			(start -0.67945 -0.3048)
			(end -0.67945 0.3048)
			(stroke
				(width 0.1)
				(type default)
			)
			(layer "B.Fab")
		)
		(fp_line
			(start -0.12065 -0.3048)
			(end -0.67945 -0.3048)
			(stroke
				(width 0.1)
				(type default)
			)
			(layer "B.Fab")
		)
		(fp_line
			(start 0.12065 -0.305054)
			(end 0.12065 -0.2794)
			(stroke
				(width 0.1)
				(type default)
			)
			(layer "B.Fab")
		)
		(fp_line
			(start 0.67945 -0.305054)
			(end 0.12065 -0.305054)
			(stroke
				(width 0.1)
				(type default)
			)
			(layer "B.Fab")
		)
		(pad "1" smd circle
			(at 0.40005 0 90)
			(size 0 0)
			(layers "B.Cu" "B.Mask" "B.Paste")
			(net "USB3_01_TXP_C")
		)
		(pad "2" smd circle
			(at -0.40005 0 90)
			(size 0 0)
			(layers "B.Cu" "B.Mask" "B.Paste")
			(net "USB3_FPNL_TXP")
		)
	)
	(footprint ""
		(layer "B.Cu")
		(at 37.4015 -102.0445 180)
		(property "Reference" "R870"
			(at 0 0 0)
			(layer "B.SilkS")
			(hide yes)
			(effects
				(font
					(size 1.27 1.27)
				)
				(justify mirror)
			)
		)
		(property "Value" ""
			(at 0 0 0)
			(layer "B.Fab")
			(effects
				(font
					(size 1.27 1.27)
				)
				(justify mirror)
			)
		)
		(duplicate_pad_numbers_are_jumpers no)
		(fp_line
			(start 0.7874 0.4064)
			(end 0.7874 -0.4064)
			(stroke
				(width 0.1524)
				(type default)
			)
			(layer "B.SilkS")
		)
		(fp_line
			(start 0.7874 -0.4064)
			(end -0.7874 -0.4064)
			(stroke
				(width 0.1524)
				(type default)
			)
			(layer "B.SilkS")
		)
		(fp_line
			(start -0.7874 0.4064)
			(end 0.7874 0.4064)
			(stroke
				(width 0.1524)
				(type default)
			)
			(layer "B.SilkS")
		)
		(fp_line
			(start -0.7874 -0.4064)
			(end -0.7874 0.4064)
			(stroke
				(width 0.1524)
				(type default)
			)
			(layer "B.SilkS")
		)
		(fp_line
			(start 0.67945 0.3048)
			(end 0.67945 -0.305054)
			(stroke
				(width 0.1)
				(type default)
			)
			(layer "B.Fab")
		)
		(fp_line
			(start 0.67945 -0.305054)
			(end 0.12065 -0.305054)
			(stroke
				(width 0.1)
				(type default)
			)
			(layer "B.Fab")
		)
		(fp_line
			(start 0.12065 0.3048)
			(end 0.67945 0.3048)
			(stroke
				(width 0.1)
				(type default)
			)
			(layer "B.Fab")
		)
		(fp_line
			(start 0.12065 0.2794)
			(end 0.12065 0.3048)
			(stroke
				(width 0.1)
				(type default)
			)
			(layer "B.Fab")
		)
		(fp_line
			(start 0.12065 -0.2794)
			(end -0.12065 -0.2794)
			(stroke
				(width 0.1)
				(type default)
			)
			(layer "B.Fab")
		)
		(fp_line
			(start 0.12065 -0.305054)
			(end 0.12065 -0.2794)
			(stroke
				(width 0.1)
				(type default)
			)
			(layer "B.Fab")
		)
		(fp_line
			(start -0.120396 0.3048)
			(end -0.120396 0.2794)
			(stroke
				(width 0.1)
				(type default)
			)
			(layer "B.Fab")
		)
		(fp_line
			(start -0.120396 0.2794)
			(end 0.12065 0.2794)
			(stroke
				(width 0.1)
				(type default)
			)
			(layer "B.Fab")
		)
		(fp_line
			(start -0.12065 -0.2794)
			(end -0.12065 -0.3048)
			(stroke
				(width 0.1)
				(type default)
			)
			(layer "B.Fab")
		)
		(fp_line
			(start -0.12065 -0.3048)
			(end -0.67945 -0.3048)
			(stroke
				(width 0.1)
				(type default)
			)
			(layer "B.Fab")
		)
		(fp_line
			(start -0.67945 0.3048)
			(end -0.120396 0.3048)
			(stroke
				(width 0.1)
				(type default)
			)
			(layer "B.Fab")
		)
		(fp_line
			(start -0.67945 -0.3048)
			(end -0.67945 0.3048)
			(stroke
				(width 0.1)
				(type default)
			)
			(layer "B.Fab")
		)
		(pad "1" smd circle
			(at 0.40005 0)
			(size 0 0)
			(layers "B.Cu" "B.Mask" "B.Paste")
			(net "P3V3_AUX")
		)
		(pad "2" smd circle
			(at -0.40005 0)
			(size 0 0)
			(layers "B.Cu" "B.Mask" "B.Paste")
			(net "PD_BIOS_MUX_EN_N")
		)
	)
	(footprint ""
		(layer "B.Cu")
		(at 40.83431 -65.776602 -90)
		(property "Reference" "R188"
			(at 0 0 90)
			(layer "B.SilkS")
			(hide yes)
			(effects
				(font
					(size 1.27 1.27)
				)
				(justify mirror)
			)
		)
		(property "Value" ""
			(at 0 0 90)
			(layer "B.Fab")
			(effects
				(font
					(size 1.27 1.27)
				)
				(justify mirror)
			)
		)
		(duplicate_pad_numbers_are_jumpers no)
		(fp_line
			(start -0.7874 0.4064)
			(end 0.7874 0.4064)
			(stroke
				(width 0.1524)
				(type default)
			)
			(layer "B.SilkS")
		)
		(fp_line
			(start 0.7874 0.4064)
			(end 0.7874 -0.4064)
			(stroke
				(width 0.1524)
				(type default)
			)
			(layer "B.SilkS")
		)
		(fp_line
			(start -0.7874 -0.4064)
			(end -0.7874 0.4064)
			(stroke
				(width 0.1524)
				(type default)
			)
			(layer "B.SilkS")
		)
		(fp_line
			(start 0.7874 -0.4064)
			(end -0.7874 -0.4064)
			(stroke
				(width 0.1524)
				(type default)
			)
			(layer "B.SilkS")
		)
		(fp_line
			(start -0.67945 0.3048)
			(end -0.120396 0.3048)
			(stroke
				(width 0.1)
				(type default)
			)
			(layer "B.Fab")
		)
		(fp_line
			(start -0.120396 0.3048)
			(end -0.120396 0.2794)
			(stroke
				(width 0.1)
				(type default)
			)
			(layer "B.Fab")
		)
		(fp_line
			(start 0.12065 0.3048)
			(end 0.67945 0.3048)
			(stroke
				(width 0.1)
				(type default)
			)
			(layer "B.Fab")
		)
		(fp_line
			(start 0.67945 0.3048)
			(end 0.67945 -0.305054)
			(stroke
				(width 0.1)
				(type default)
			)
			(layer "B.Fab")
		)
		(fp_line
			(start -0.120396 0.2794)
			(end 0.12065 0.2794)
			(stroke
				(width 0.1)
				(type default)
			)
			(layer "B.Fab")
		)
		(fp_line
			(start 0.12065 0.2794)
			(end 0.12065 0.3048)
			(stroke
				(width 0.1)
				(type default)
			)
			(layer "B.Fab")
		)
		(fp_line
			(start -0.12065 -0.2794)
			(end -0.12065 -0.3048)
			(stroke
				(width 0.1)
				(type default)
			)
			(layer "B.Fab")
		)
		(fp_line
			(start 0.12065 -0.2794)
			(end -0.12065 -0.2794)
			(stroke
				(width 0.1)
				(type default)
			)
			(layer "B.Fab")
		)
		(fp_line
			(start -0.67945 -0.3048)
			(end -0.67945 0.3048)
			(stroke
				(width 0.1)
				(type default)
			)
			(layer "B.Fab")
		)
		(fp_line
			(start -0.12065 -0.3048)
			(end -0.67945 -0.3048)
			(stroke
				(width 0.1)
				(type default)
			)
			(layer "B.Fab")
		)
		(fp_line
			(start 0.12065 -0.305054)
			(end 0.12065 -0.2794)
			(stroke
				(width 0.1)
				(type default)
			)
			(layer "B.Fab")
		)
		(fp_line
			(start 0.67945 -0.305054)
			(end 0.12065 -0.305054)
			(stroke
				(width 0.1)
				(type default)
			)
			(layer "B.Fab")
		)
		(pad "1" smd circle
			(at 0.40005 0 90)
			(size 0 0)
			(layers "B.Cu" "B.Mask" "B.Paste")
			(net "P1V2_P1V0_I3C_VDDL1")
		)
		(pad "2" smd circle
			(at -0.40005 0 90)
			(size 0 0)
			(layers "B.Cu" "B.Mask" "B.Paste")
			(net "I3C3_SPD_SCL")
		)
	)
	(footprint ""
		(layer "B.Cu")
		(at 34.417 -36.195 90)
		(property "Reference" "R121"
			(at 0 0 90)
			(layer "B.SilkS")
			(hide yes)
			(effects
				(font
					(size 1.27 1.27)
				)
				(justify mirror)
			)
		)
		(property "Value" ""
			(at 0 0 90)
			(layer "B.Fab")
			(effects
				(font
					(size 1.27 1.27)
				)
				(justify mirror)
			)
		)
		(duplicate_pad_numbers_are_jumpers no)
		(fp_line
			(start 0.7874 -0.4064)
			(end -0.7874 -0.4064)
			(stroke
				(width 0.1524)
				(type default)
			)
			(layer "B.SilkS")
		)
		(fp_line
			(start -0.7874 -0.4064)
			(end -0.7874 0.4064)
			(stroke
				(width 0.1524)
				(type default)
			)
			(layer "B.SilkS")
		)
		(fp_line
			(start 0.7874 0.4064)
			(end 0.7874 -0.4064)
			(stroke
				(width 0.1524)
				(type default)
			)
			(layer "B.SilkS")
		)
		(fp_line
			(start -0.7874 0.4064)
			(end 0.7874 0.4064)
			(stroke
				(width 0.1524)
				(type default)
			)
			(layer "B.SilkS")
		)
		(fp_line
			(start 0.67945 -0.305054)
			(end 0.12065 -0.305054)
			(stroke
				(width 0.1)
				(type default)
			)
			(layer "B.Fab")
		)
		(fp_line
			(start 0.12065 -0.305054)
			(end 0.12065 -0.2794)
			(stroke
				(width 0.1)
				(type default)
			)
			(layer "B.Fab")
		)
		(fp_line
			(start -0.12065 -0.3048)
			(end -0.67945 -0.3048)
			(stroke
				(width 0.1)
				(type default)
			)
			(layer "B.Fab")
		)
		(fp_line
			(start -0.67945 -0.3048)
			(end -0.67945 0.3048)
			(stroke
				(width 0.1)
				(type default)
			)
			(layer "B.Fab")
		)
		(fp_line
			(start 0.12065 -0.2794)
			(end -0.12065 -0.2794)
			(stroke
				(width 0.1)
				(type default)
			)
			(layer "B.Fab")
		)
		(fp_line
			(start -0.12065 -0.2794)
			(end -0.12065 -0.3048)
			(stroke
				(width 0.1)
				(type default)
			)
			(layer "B.Fab")
		)
		(fp_line
			(start 0.12065 0.2794)
			(end 0.12065 0.3048)
			(stroke
				(width 0.1)
				(type default)
			)
			(layer "B.Fab")
		)
		(fp_line
			(start -0.120396 0.2794)
			(end 0.12065 0.2794)
			(stroke
				(width 0.1)
				(type default)
			)
			(layer "B.Fab")
		)
		(fp_line
			(start 0.67945 0.3048)
			(end 0.67945 -0.305054)
			(stroke
				(width 0.1)
				(type default)
			)
			(layer "B.Fab")
		)
		(fp_line
			(start 0.12065 0.3048)
			(end 0.67945 0.3048)
			(stroke
				(width 0.1)
				(type default)
			)
			(layer "B.Fab")
		)
		(fp_line
			(start -0.120396 0.3048)
			(end -0.120396 0.2794)
			(stroke
				(width 0.1)
				(type default)
			)
			(layer "B.Fab")
		)
		(fp_line
			(start -0.67945 0.3048)
			(end -0.120396 0.3048)
			(stroke
				(width 0.1)
				(type default)
			)
			(layer "B.Fab")
		)
		(pad "1" smd circle
			(at 0.40005 0 270)
			(size 0 0)
			(layers "B.Cu" "B.Mask" "B.Paste")
			(net "FM_CPU_RMCA_CATERR_LVT3_R_N")
		)
		(pad "2" smd circle
			(at -0.40005 0 270)
			(size 0 0)
			(layers "B.Cu" "B.Mask" "B.Paste")
			(net "FM_CPU_MSMI_CATERR_LVT3_N")
		)
	)
	(footprint ""
		(layer "B.Cu")
		(at 12.7 -90.043 90)
		(property "Reference" "R641"
			(at 0 0 90)
			(layer "B.SilkS")
			(hide yes)
			(effects
				(font
					(size 1.27 1.27)
				)
				(justify mirror)
			)
		)
		(property "Value" ""
			(at 0 0 90)
			(layer "B.Fab")
			(effects
				(font
					(size 1.27 1.27)
				)
				(justify mirror)
			)
		)
		(duplicate_pad_numbers_are_jumpers no)
		(fp_line
			(start 0.7874 -0.4064)
			(end -0.7874 -0.4064)
			(stroke
				(width 0.1524)
				(type default)
			)
			(layer "B.SilkS")
		)
		(fp_line
			(start -0.7874 -0.4064)
			(end -0.7874 0.4064)
			(stroke
				(width 0.1524)
				(type default)
			)
			(layer "B.SilkS")
		)
		(fp_line
			(start 0.7874 0.4064)
			(end 0.7874 -0.4064)
			(stroke
				(width 0.1524)
				(type default)
			)
			(layer "B.SilkS")
		)
		(fp_line
			(start -0.7874 0.4064)
			(end 0.7874 0.4064)
			(stroke
				(width 0.1524)
				(type default)
			)
			(layer "B.SilkS")
		)
		(fp_line
			(start 0.67945 -0.305054)
			(end 0.12065 -0.305054)
			(stroke
				(width 0.1)
				(type default)
			)
			(layer "B.Fab")
		)
		(fp_line
			(start 0.12065 -0.305054)
			(end 0.12065 -0.2794)
			(stroke
				(width 0.1)
				(type default)
			)
			(layer "B.Fab")
		)
		(fp_line
			(start -0.12065 -0.3048)
			(end -0.67945 -0.3048)
			(stroke
				(width 0.1)
				(type default)
			)
			(layer "B.Fab")
		)
		(fp_line
			(start -0.67945 -0.3048)
			(end -0.67945 0.3048)
			(stroke
				(width 0.1)
				(type default)
			)
			(layer "B.Fab")
		)
		(fp_line
			(start 0.12065 -0.2794)
			(end -0.12065 -0.2794)
			(stroke
				(width 0.1)
				(type default)
			)
			(layer "B.Fab")
		)
		(fp_line
			(start -0.12065 -0.2794)
			(end -0.12065 -0.3048)
			(stroke
				(width 0.1)
				(type default)
			)
			(layer "B.Fab")
		)
		(fp_line
			(start 0.12065 0.2794)
			(end 0.12065 0.3048)
			(stroke
				(width 0.1)
				(type default)
			)
			(layer "B.Fab")
		)
		(fp_line
			(start -0.120396 0.2794)
			(end 0.12065 0.2794)
			(stroke
				(width 0.1)
				(type default)
			)
			(layer "B.Fab")
		)
		(fp_line
			(start 0.67945 0.3048)
			(end 0.67945 -0.305054)
			(stroke
				(width 0.1)
				(type default)
			)
			(layer "B.Fab")
		)
		(fp_line
			(start 0.12065 0.3048)
			(end 0.67945 0.3048)
			(stroke
				(width 0.1)
				(type default)
			)
			(layer "B.Fab")
		)
		(fp_line
			(start -0.120396 0.3048)
			(end -0.120396 0.2794)
			(stroke
				(width 0.1)
				(type default)
			)
			(layer "B.Fab")
		)
		(fp_line
			(start -0.67945 0.3048)
			(end -0.120396 0.3048)
			(stroke
				(width 0.1)
				(type default)
			)
			(layer "B.Fab")
		)
		(pad "1" smd circle
			(at 0.40005 0 270)
			(size 0 0)
			(layers "B.Cu" "B.Mask" "B.Paste")
			(net "P3V3_AUX")
		)
		(pad "2" smd circle
			(at -0.40005 0 270)
			(size 0 0)
			(layers "B.Cu" "B.Mask" "B.Paste")
			(net "RST_BMC_SELF_HW_R2")
		)
	)
)
